(kicad_pcb
	(version 20260206)
	(generator "pcbnew")
	(generator_version "10.0")
	(general
		(thickness 1.6)
		(legacy_teardrops no)
	)
	(paper "A4")
	(title_block
		(title "03242023_DA0F0TMBIJ0_F0T_Motherboard_J_brd_V01_OCP.brd")
		(comment 1 "Grand Teton / footprints 5762-5767 of 6105")
	)
	(layers
		(0 "F.Cu" signal "TOP")
		(4 "In1.Cu" signal "GND")
		(6 "In2.Cu" signal "IN1")
		(8 "In3.Cu" signal "GND1")
		(10 "In4.Cu" signal "IN2")
		(12 "In5.Cu" signal "GND2")
		(14 "In6.Cu" signal "IN3")
		(16 "In7.Cu" signal "GND3")
		(18 "In8.Cu" signal "VCC")
		(20 "In9.Cu" signal "VCC1")
		(22 "In10.Cu" signal "GND4")
		(24 "In11.Cu" signal "IN4")
		(26 "In12.Cu" signal "GND5")
		(28 "In13.Cu" signal "IN5")
		(30 "In14.Cu" signal "GND6")
		(32 "In15.Cu" signal "IN6")
		(34 "In16.Cu" signal "GND7")
		(2 "B.Cu" signal "BOTTOM")
		(9 "F.Adhes" user "F.Adhesive")
		(11 "B.Adhes" user "B.Adhesive")
		(13 "F.Paste" user "Package Geometry/Pastemask Top")
		(15 "B.Paste" user "Package Geometry/Pastemask Bottom")
		(5 "F.SilkS" user "Ref Des/Silkscreen Top")
		(7 "B.SilkS" user "Ref Des/Silkscreen Bottom")
		(1 "F.Mask" user "Board Geometry/Soldermask Top")
		(3 "B.Mask" user "Board Geometry/Soldermask Bottom")
		(17 "Dwgs.User" user "User.Drawings")
		(19 "Cmts.User" user "User.Comments")
		(21 "Eco1.User" user "User.Eco1")
		(23 "Eco2.User" user "User.Eco2")
		(25 "Edge.Cuts" user "Board Geometry/Outline")
		(27 "Margin" user)
		(31 "F.CrtYd" user "Package Geometry/Place Bound Top")
		(29 "B.CrtYd" user "Package Geometry/Place Bound Bottom")
		(35 "F.Fab" user "Ref Des/Assembly Top")
		(33 "B.Fab" user "Ref Des/Assembly Bottom")
	)
	(footprint ""
		(layer "B.Cu")
		(at 378.099574 -2.156206)
		(property "Reference" "J64"
			(at 4.651756 1.013206 270)
			(unlocked yes)
			(layer "B.SilkS")
			(effects
				(font
					(size 0.7874 0.5842)
					(thickness 0.1524)
				)
				(justify left mirror)
			)
		)
		(property "Value" ""
			(at 0 0 0)
			(layer "B.Fab")
			(effects
				(font
					(size 1.27 1.27)
				)
				(justify mirror)
			)
		)
		(duplicate_pad_numbers_are_jumpers no)
		(fp_line
			(start -1.2192 -2.1082)
			(end -1.2192 2.1082)
			(stroke
				(width 0.1524)
				(type default)
			)
			(layer "B.SilkS")
		)
		(fp_line
			(start -1.2192 2.1082)
			(end 1.2192 2.1082)
			(stroke
				(width 0.1524)
				(type default)
			)
			(layer "B.SilkS")
		)
		(fp_line
			(start 1.2192 -2.1082)
			(end -1.2192 -2.1082)
			(stroke
				(width 0.1524)
				(type default)
			)
			(layer "B.SilkS")
		)
		(fp_line
			(start 1.2192 2.1082)
			(end 1.2192 -2.1082)
			(stroke
				(width 0.1524)
				(type default)
			)
			(layer "B.SilkS")
		)
		(pad "" np_thru_hole circle
			(at -3.4671 -1.27 270)
			(size 1.0414 1.0414)
			(drill 1.0414)
			(layers "*.Cu" "*.Mask")
			(clearance 0.381)
			(thermal_gap 0.381)
		)
		(pad "" np_thru_hole circle
			(at -3.4671 1.27 270)
			(size 1.0414 1.0414)
			(drill 1.0414)
			(layers "*.Cu" "*.Mask")
			(clearance 0.381)
			(thermal_gap 0.381)
		)
		(pad "" np_thru_hole circle
			(at 2.8829 -1.27 270)
			(size 1.0414 1.0414)
			(drill 1.0414)
			(layers "*.Cu" "*.Mask")
			(clearance 0.381)
			(thermal_gap 0.381)
		)
		(pad "" np_thru_hole circle
			(at 2.8829 1.27 270)
			(size 1.0414 1.0414)
			(drill 1.0414)
			(layers "*.Cu" "*.Mask")
			(clearance 0.381)
			(thermal_gap 0.381)
		)
		(pad "1" smd rect
			(at -0.8255 -0.249936 270)
			(size 0.3048 0.508)
			(layers "B.Cu" "B.Mask" "B.Paste")
			(net "DELTA_L_85_5INCH_BOT_DP")
		)
		(pad "2" smd rect
			(at -0.8255 0.249936 270)
			(size 0.3048 0.508)
			(layers "B.Cu" "B.Mask" "B.Paste")
			(net "DELTA_L_85_5INCH_BOT_DN")
		)
		(pad "3" smd circle
			(at 0 0 180)
			(size 0 0)
			(layers "B.Cu" "B.Mask" "B.Paste")
			(net "DELTA_L_GND_1")
		)
		(zone
			(layers "F.Cu" "B.Cu" "In1.Cu" "In2.Cu" "In3.Cu" "In4.Cu" "In5.Cu" "In6.Cu"
				"In7.Cu" "In8.Cu" "In9.Cu" "In10.Cu" "In11.Cu" "In12.Cu" "In13.Cu" "In14.Cu"
				"In15.Cu" "In16.Cu"
			)
			(hatch none 0.5)
			(connect_pads
				(clearance 0)
			)
			(min_thickness 0.25)
			(keepout
				(tracks not_allowed)
				(vias allowed)
				(pads allowed)
				(copperpour not_allowed)
				(footprints allowed)
			)
			(placement
				(enabled no)
				(sheetname "")
			)
			(fill
				(thermal_gap 0.5)
				(thermal_bridge_width 0.5)
				(island_removal_mode 0)
			)
			(polygon
				(pts
					(arc
						(start 375.559574 -3.426206)
						(mid 373.705374 -3.426206)
						(end 375.559574 -3.426206)
					)
				)
			)
		)
		(zone
			(layers "F.Cu" "B.Cu" "In1.Cu" "In2.Cu" "In3.Cu" "In4.Cu" "In5.Cu" "In6.Cu"
				"In7.Cu" "In8.Cu" "In9.Cu" "In10.Cu" "In11.Cu" "In12.Cu" "In13.Cu" "In14.Cu"
				"In15.Cu" "In16.Cu"
			)
			(hatch none 0.5)
			(connect_pads
				(clearance 0)
			)
			(min_thickness 0.25)
			(keepout
				(tracks not_allowed)
				(vias allowed)
				(pads allowed)
				(copperpour not_allowed)
				(footprints allowed)
			)
			(placement
				(enabled no)
				(sheetname "")
			)
			(fill
				(thermal_gap 0.5)
				(thermal_bridge_width 0.5)
				(island_removal_mode 0)
			)
			(polygon
				(pts
					(arc
						(start 375.559574 -0.886206)
						(mid 373.705374 -0.886206)
						(end 375.559574 -0.886206)
					)
				)
			)
		)
		(zone
			(layers "F.Cu" "B.Cu" "In1.Cu" "In2.Cu" "In3.Cu" "In4.Cu" "In5.Cu" "In6.Cu"
				"In7.Cu" "In8.Cu" "In9.Cu" "In10.Cu" "In11.Cu" "In12.Cu" "In13.Cu" "In14.Cu"
				"In15.Cu" "In16.Cu"
			)
			(hatch none 0.5)
			(connect_pads
				(clearance 0)
			)
			(min_thickness 0.25)
			(keepout
				(tracks not_allowed)
				(vias allowed)
				(pads allowed)
				(copperpour not_allowed)
				(footprints allowed)
			)
			(placement
				(enabled no)
				(sheetname "")
			)
			(fill
				(thermal_gap 0.5)
				(thermal_bridge_width 0.5)
				(island_removal_mode 0)
			)
			(polygon
				(pts
					(arc
						(start 381.909574 -3.426206)
						(mid 380.055374 -3.426206)
						(end 381.909574 -3.426206)
					)
				)
			)
		)
		(zone
			(layers "F.Cu" "B.Cu" "In1.Cu" "In2.Cu" "In3.Cu" "In4.Cu" "In5.Cu" "In6.Cu"
				"In7.Cu" "In8.Cu" "In9.Cu" "In10.Cu" "In11.Cu" "In12.Cu" "In13.Cu" "In14.Cu"
				"In15.Cu" "In16.Cu"
			)
			(hatch none 0.5)
			(connect_pads
				(clearance 0)
			)
			(min_thickness 0.25)
			(keepout
				(tracks not_allowed)
				(vias allowed)
				(pads allowed)
				(copperpour not_allowed)
				(footprints allowed)
			)
			(placement
				(enabled no)
				(sheetname "")
			)
			(fill
				(thermal_gap 0.5)
				(thermal_bridge_width 0.5)
				(island_removal_mode 0)
			)
			(polygon
				(pts
					(arc
						(start 381.909574 -0.886206)
						(mid 380.055374 -0.886206)
						(end 381.909574 -0.886206)
					)
				)
			)
		)
		(zone
			(layer "B.Cu")
			(hatch none 0.5)
			(connect_pads
				(clearance 0)
			)
			(min_thickness 0.25)
			(keepout
				(tracks not_allowed)
				(vias allowed)
				(pads allowed)
				(copperpour not_allowed)
				(footprints allowed)
			)
			(placement
				(enabled no)
				(sheetname "")
			)
			(fill
				(thermal_gap 0.5)
				(thermal_bridge_width 0.5)
				(island_removal_mode 0)
			)
			(polygon
				(pts
					(xy 376.981974 -2.704846) (xy 376.981974 -2.609342) (xy 377.578874 -2.609342) (xy 377.578874 -2.202942)
					(xy 376.981974 -2.202942) (xy 376.981974 -2.10947) (xy 377.578874 -2.10947) (xy 377.578874 -1.70307)
					(xy 376.981974 -1.70307) (xy 376.981974 -1.607566) (xy 377.680474 -1.607566) (xy 377.680474 -2.704846)
				)
			)
		)
	)
	(footprint ""
		(layer "B.Cu")
		(at 107.457494 -252.17628 -90)
		(property "Reference" "C333"
			(at 0 0 90)
			(layer "B.SilkS")
			(hide yes)
			(effects
				(font
					(size 1.27 1.27)
				)
				(justify mirror)
			)
		)
		(property "Value" ""
			(at 0 0 90)
			(layer "B.Fab")
			(effects
				(font
					(size 1.27 1.27)
				)
				(justify mirror)
			)
		)
		(duplicate_pad_numbers_are_jumpers no)
		(fp_line
			(start -1.524 0.762)
			(end 1.524 0.762)
			(stroke
				(width 0.1524)
				(type default)
			)
			(layer "B.SilkS")
		)
		(fp_line
			(start 1.524 0.762)
			(end 1.524 -0.762)
			(stroke
				(width 0.1524)
				(type default)
			)
			(layer "B.SilkS")
		)
		(fp_line
			(start -1.524 -0.762)
			(end -1.524 0.762)
			(stroke
				(width 0.1524)
				(type default)
			)
			(layer "B.SilkS")
		)
		(fp_line
			(start 1.524 -0.762)
			(end -1.524 -0.762)
			(stroke
				(width 0.1524)
				(type default)
			)
			(layer "B.SilkS")
		)
		(fp_line
			(start -1.1049 0.724916)
			(end -1.1049 -0.724916)
			(stroke
				(width 0.1)
				(type default)
			)
			(layer "B.Fab")
		)
		(fp_line
			(start 1.1049 0.724916)
			(end -1.1049 0.724916)
			(stroke
				(width 0.1)
				(type default)
			)
			(layer "B.Fab")
		)
		(fp_line
			(start -1.1049 -0.724916)
			(end 1.1049 -0.724916)
			(stroke
				(width 0.1)
				(type default)
			)
			(layer "B.Fab")
		)
		(fp_line
			(start 1.1049 -0.724916)
			(end 1.1049 0.724916)
			(stroke
				(width 0.1)
				(type default)
			)
			(layer "B.Fab")
		)
		(pad "1" smd rect
			(at 0.889 0 270)
			(size 1.016 1.27)
			(layers "B.Cu" "B.Mask" "B.Paste")
			(net "PVCCIN_CPU1")
		)
		(pad "2" smd rect
			(at -0.889 0 270)
			(size 1.016 1.27)
			(layers "B.Cu" "B.Mask" "B.Paste")
			(net "GND")
		)
	)
	(footprint ""
		(layer "B.Cu")
		(at 182.867046 -13.60043 -90)
		(property "Reference" "R600"
			(at 0 0 90)
			(layer "B.SilkS")
			(hide yes)
			(effects
				(font
					(size 1.27 1.27)
				)
				(justify mirror)
			)
		)
		(property "Value" ""
			(at 0 0 90)
			(layer "B.Fab")
			(effects
				(font
					(size 1.27 1.27)
				)
				(justify mirror)
			)
		)
		(duplicate_pad_numbers_are_jumpers no)
		(fp_line
			(start -0.7874 0.4064)
			(end 0.7874 0.4064)
			(stroke
				(width 0.1524)
				(type default)
			)
			(layer "B.SilkS")
		)
		(fp_line
			(start 0.7874 0.4064)
			(end 0.7874 -0.4064)
			(stroke
				(width 0.1524)
				(type default)
			)
			(layer "B.SilkS")
		)
		(fp_line
			(start -0.7874 -0.4064)
			(end -0.7874 0.4064)
			(stroke
				(width 0.1524)
				(type default)
			)
			(layer "B.SilkS")
		)
		(fp_line
			(start 0.7874 -0.4064)
			(end -0.7874 -0.4064)
			(stroke
				(width 0.1524)
				(type default)
			)
			(layer "B.SilkS")
		)
		(fp_line
			(start -0.67945 0.3048)
			(end -0.120396 0.3048)
			(stroke
				(width 0.1)
				(type default)
			)
			(layer "B.Fab")
		)
		(fp_line
			(start -0.120396 0.3048)
			(end -0.120396 0.2794)
			(stroke
				(width 0.1)
				(type default)
			)
			(layer "B.Fab")
		)
		(fp_line
			(start 0.12065 0.3048)
			(end 0.67945 0.3048)
			(stroke
				(width 0.1)
				(type default)
			)
			(layer "B.Fab")
		)
		(fp_line
			(start 0.67945 0.3048)
			(end 0.67945 -0.305054)
			(stroke
				(width 0.1)
				(type default)
			)
			(layer "B.Fab")
		)
		(fp_line
			(start -0.120396 0.2794)
			(end 0.12065 0.2794)
			(stroke
				(width 0.1)
				(type default)
			)
			(layer "B.Fab")
		)
		(fp_line
			(start 0.12065 0.2794)
			(end 0.12065 0.3048)
			(stroke
				(width 0.1)
				(type default)
			)
			(layer "B.Fab")
		)
		(fp_line
			(start -0.12065 -0.2794)
			(end -0.12065 -0.3048)
			(stroke
				(width 0.1)
				(type default)
			)
			(layer "B.Fab")
		)
		(fp_line
			(start 0.12065 -0.2794)
			(end -0.12065 -0.2794)
			(stroke
				(width 0.1)
				(type default)
			)
			(layer "B.Fab")
		)
		(fp_line
			(start -0.67945 -0.3048)
			(end -0.67945 0.3048)
			(stroke
				(width 0.1)
				(type default)
			)
			(layer "B.Fab")
		)
		(fp_line
			(start -0.12065 -0.3048)
			(end -0.67945 -0.3048)
			(stroke
				(width 0.1)
				(type default)
			)
			(layer "B.Fab")
		)
		(fp_line
			(start 0.12065 -0.305054)
			(end 0.12065 -0.2794)
			(stroke
				(width 0.1)
				(type default)
			)
			(layer "B.Fab")
		)
		(fp_line
			(start 0.67945 -0.305054)
			(end 0.12065 -0.305054)
			(stroke
				(width 0.1)
				(type default)
			)
			(layer "B.Fab")
		)
		(pad "1" smd circle
			(at 0.40005 0 90)
			(size 0 0)
			(layers "B.Cu" "B.Mask" "B.Paste")
			(net "I3C_SPD_DDREFGH_CPU1_BMC_R_SDA")
		)
		(pad "2" smd circle
			(at -0.40005 0 90)
			(size 0 0)
			(layers "B.Cu" "B.Mask" "B.Paste")
			(net "I3C_SPD_DDREFGH_CPU1_BMC_SDA")
		)
	)
	(footprint ""
		(layer "B.Cu")
		(at 384.484372 -331.58938 -90)
		(property "Reference" "PC246_P0_8"
			(at 0 0 90)
			(layer "B.SilkS")
			(hide yes)
			(effects
				(font
					(size 1.27 1.27)
				)
				(justify mirror)
			)
		)
		(property "Value" ""
			(at 0 0 90)
			(layer "B.Fab")
			(effects
				(font
					(size 1.27 1.27)
				)
				(justify mirror)
			)
		)
		(duplicate_pad_numbers_are_jumpers no)
		(fp_line
			(start -1.524 0.762)
			(end 1.524 0.762)
			(stroke
				(width 0.1524)
				(type default)
			)
			(layer "B.SilkS")
		)
		(fp_line
			(start 1.524 0.762)
			(end 1.524 -0.762)
			(stroke
				(width 0.1524)
				(type default)
			)
			(layer "B.SilkS")
		)
		(fp_line
			(start -1.524 -0.762)
			(end -1.524 0.762)
			(stroke
				(width 0.1524)
				(type default)
			)
			(layer "B.SilkS")
		)
		(fp_line
			(start 1.524 -0.762)
			(end -1.524 -0.762)
			(stroke
				(width 0.1524)
				(type default)
			)
			(layer "B.SilkS")
		)
		(fp_line
			(start -1.1049 0.724916)
			(end -1.1049 -0.724916)
			(stroke
				(width 0.1)
				(type default)
			)
			(layer "B.Fab")
		)
		(fp_line
			(start 1.1049 0.724916)
			(end -1.1049 0.724916)
			(stroke
				(width 0.1)
				(type default)
			)
			(layer "B.Fab")
		)
		(fp_line
			(start -1.1049 -0.724916)
			(end 1.1049 -0.724916)
			(stroke
				(width 0.1)
				(type default)
			)
			(layer "B.Fab")
		)
		(fp_line
			(start 1.1049 -0.724916)
			(end 1.1049 0.724916)
			(stroke
				(width 0.1)
				(type default)
			)
			(layer "B.Fab")
		)
		(pad "1" smd rect
			(at 0.889 0 270)
			(size 1.016 1.27)
			(layers "B.Cu" "B.Mask" "B.Paste")
			(net "PVCCIN_CPU0")
		)
		(pad "2" smd rect
			(at -0.889 0 270)
			(size 1.016 1.27)
			(layers "B.Cu" "B.Mask" "B.Paste")
			(net "GND")
		)
	)
	(footprint ""
		(layer "B.Cu")
		(at 196.544946 -319.268856 180)
		(property "Reference" "C81"
			(at 0 0 0)
			(layer "B.SilkS")
			(hide yes)
			(effects
				(font
					(size 1.27 1.27)
				)
				(justify mirror)
			)
		)
		(property "Value" ""
			(at 0 0 0)
			(layer "B.Fab")
			(effects
				(font
					(size 1.27 1.27)
				)
				(justify mirror)
			)
		)
		(duplicate_pad_numbers_are_jumpers no)
		(fp_line
			(start 0.7874 0.4064)
			(end 0.7874 -0.4064)
			(stroke
				(width 0.1524)
				(type default)
			)
			(layer "B.SilkS")
		)
		(fp_line
			(start 0.7874 -0.4064)
			(end -0.7874 -0.4064)
			(stroke
				(width 0.1524)
				(type default)
			)
			(layer "B.SilkS")
		)
		(fp_line
			(start -0.7874 0.4064)
			(end 0.7874 0.4064)
			(stroke
				(width 0.1524)
				(type default)
			)
			(layer "B.SilkS")
		)
		(fp_line
			(start -0.7874 -0.4064)
			(end -0.7874 0.4064)
			(stroke
				(width 0.1524)
				(type default)
			)
			(layer "B.SilkS")
		)
		(fp_line
			(start 0.67945 0.3048)
			(end 0.67945 -0.305054)
			(stroke
				(width 0.1)
				(type default)
			)
			(layer "B.Fab")
		)
		(fp_line
			(start 0.67945 -0.305054)
			(end 0.12065 -0.305054)
			(stroke
				(width 0.1)
				(type default)
			)
			(layer "B.Fab")
		)
		(fp_line
			(start 0.12065 0.3048)
			(end 0.67945 0.3048)
			(stroke
				(width 0.1)
				(type default)
			)
			(layer "B.Fab")
		)
		(fp_line
			(start 0.12065 0.2794)
			(end 0.12065 0.3048)
			(stroke
				(width 0.1)
				(type default)
			)
			(layer "B.Fab")
		)
		(fp_line
			(start 0.12065 -0.2794)
			(end -0.12065 -0.2794)
			(stroke
				(width 0.1)
				(type default)
			)
			(layer "B.Fab")
		)
		(fp_line
			(start 0.12065 -0.305054)
			(end 0.12065 -0.2794)
			(stroke
				(width 0.1)
				(type default)
			)
			(layer "B.Fab")
		)
		(fp_line
			(start -0.120396 0.3048)
			(end -0.120396 0.2794)
			(stroke
				(width 0.1)
				(type default)
			)
			(layer "B.Fab")
		)
		(fp_line
			(start -0.120396 0.2794)
			(end 0.12065 0.2794)
			(stroke
				(width 0.1)
				(type default)
			)
			(layer "B.Fab")
		)
		(fp_line
			(start -0.12065 -0.2794)
			(end -0.12065 -0.3048)
			(stroke
				(width 0.1)
				(type default)
			)
			(layer "B.Fab")
		)
		(fp_line
			(start -0.12065 -0.3048)
			(end -0.67945 -0.3048)
			(stroke
				(width 0.1)
				(type default)
			)
			(layer "B.Fab")
		)
		(fp_line
			(start -0.67945 0.3048)
			(end -0.120396 0.3048)
			(stroke
				(width 0.1)
				(type default)
			)
			(layer "B.Fab")
		)
		(fp_line
			(start -0.67945 -0.3048)
			(end -0.67945 0.3048)
			(stroke
				(width 0.1)
				(type default)
			)
			(layer "B.Fab")
		)
		(pad "1" smd circle
			(at 0.40005 0)
			(size 0 0)
			(layers "B.Cu" "B.Mask" "B.Paste")
			(net "P3V3_AUX")
		)
		(pad "2" smd circle
			(at -0.40005 0)
			(size 0 0)
			(layers "B.Cu" "B.Mask" "B.Paste")
			(net "GND")
		)
	)
	(footprint ""
		(layer "B.Cu")
		(at 179.168552 -192.699894 -90)
		(property "Reference" "R93"
			(at 0 0 90)
			(layer "B.SilkS")
			(hide yes)
			(effects
				(font
					(size 1.27 1.27)
				)
				(justify mirror)
			)
		)
		(property "Value" ""
			(at 0 0 90)
			(layer "B.Fab")
			(effects
				(font
					(size 1.27 1.27)
				)
				(justify mirror)
			)
		)
		(duplicate_pad_numbers_are_jumpers no)
		(fp_line
			(start -0.7874 0.4064)
			(end 0.7874 0.4064)
			(stroke
				(width 0.1524)
				(type default)
			)
			(layer "B.SilkS")
		)
		(fp_line
			(start 0.7874 0.4064)
			(end 0.7874 -0.4064)
			(stroke
				(width 0.1524)
				(type default)
			)
			(layer "B.SilkS")
		)
		(fp_line
			(start -0.7874 -0.4064)
			(end -0.7874 0.4064)
			(stroke
				(width 0.1524)
				(type default)
			)
			(layer "B.SilkS")
		)
		(fp_line
			(start 0.7874 -0.4064)
			(end -0.7874 -0.4064)
			(stroke
				(width 0.1524)
				(type default)
			)
			(layer "B.SilkS")
		)
		(fp_line
			(start -0.67945 0.3048)
			(end -0.120396 0.3048)
			(stroke
				(width 0.1)
				(type default)
			)
			(layer "B.Fab")
		)
		(fp_line
			(start -0.120396 0.3048)
			(end -0.120396 0.2794)
			(stroke
				(width 0.1)
				(type default)
			)
			(layer "B.Fab")
		)
		(fp_line
			(start 0.12065 0.3048)
			(end 0.67945 0.3048)
			(stroke
				(width 0.1)
				(type default)
			)
			(layer "B.Fab")
		)
		(fp_line
			(start 0.67945 0.3048)
			(end 0.67945 -0.305054)
			(stroke
				(width 0.1)
				(type default)
			)
			(layer "B.Fab")
		)
		(fp_line
			(start -0.120396 0.2794)
			(end 0.12065 0.2794)
			(stroke
				(width 0.1)
				(type default)
			)
			(layer "B.Fab")
		)
		(fp_line
			(start 0.12065 0.2794)
			(end 0.12065 0.3048)
			(stroke
				(width 0.1)
				(type default)
			)
			(layer "B.Fab")
		)
		(fp_line
			(start -0.12065 -0.2794)
			(end -0.12065 -0.3048)
			(stroke
				(width 0.1)
				(type default)
			)
			(layer "B.Fab")
		)
		(fp_line
			(start 0.12065 -0.2794)
			(end -0.12065 -0.2794)
			(stroke
				(width 0.1)
				(type default)
			)
			(layer "B.Fab")
		)
		(fp_line
			(start -0.67945 -0.3048)
			(end -0.67945 0.3048)
			(stroke
				(width 0.1)
				(type default)
			)
			(layer "B.Fab")
		)
		(fp_line
			(start -0.12065 -0.3048)
			(end -0.67945 -0.3048)
			(stroke
				(width 0.1)
				(type default)
			)
			(layer "B.Fab")
		)
		(fp_line
			(start 0.12065 -0.305054)
			(end 0.12065 -0.2794)
			(stroke
				(width 0.1)
				(type default)
			)
			(layer "B.Fab")
		)
		(fp_line
			(start 0.67945 -0.305054)
			(end 0.12065 -0.305054)
			(stroke
				(width 0.1)
				(type default)
			)
			(layer "B.Fab")
		)
		(pad "1" smd circle
			(at 0.40005 0 90)
			(size 0 0)
			(layers "B.Cu" "B.Mask" "B.Paste")
			(net "PVNN_TERM_CPU1")
		)
		(pad "2" smd circle
			(at -0.40005 0 90)
			(size 0 0)
			(layers "B.Cu" "B.Mask" "B.Paste")
			(net "PU_CPU1_UPI3_AC_COUPLING")
		)
	)
)
